(kicad_pcb
	(version 20260206)
	(generator "pcbnew")
	(generator_version "10.0")
	(general
		(thickness 1.6)
		(legacy_teardrops no)
	)
	(paper "A4")
	(title_block
		(title "01162023_DA0F0TEBIF0_F0T_Expander_BD_F_brd_V02_OCP.brd")
		(comment 1 "Grand Teton / footprints 804-808 of 9728")
	)
	(layers
		(0 "F.Cu" signal "TOP")
		(4 "In1.Cu" signal "GND")
		(6 "In2.Cu" signal "VCC")
		(8 "In3.Cu" signal "VCC1")
		(10 "In4.Cu" signal "GND1")
		(12 "In5.Cu" signal "IN1")
		(14 "In6.Cu" signal "GND2")
		(16 "In7.Cu" signal "IN2")
		(18 "In8.Cu" signal "GND3")
		(20 "In9.Cu" signal "IN3")
		(22 "In10.Cu" signal "GND4")
		(24 "In11.Cu" signal "IN4")
		(26 "In12.Cu" signal "GND5")
		(28 "In13.Cu" signal "IN5")
		(30 "In14.Cu" signal "GND6")
		(32 "In15.Cu" signal "IN6")
		(34 "In16.Cu" signal "GND7")
		(2 "B.Cu" signal "BOTTOM")
		(9 "F.Adhes" user "F.Adhesive")
		(11 "B.Adhes" user "B.Adhesive")
		(13 "F.Paste" user "Package Geometry/Pastemask Top")
		(15 "B.Paste" user "Package Geometry/Pastemask Bottom")
		(5 "F.SilkS" user "Ref Des/Silkscreen Top")
		(7 "B.SilkS" user "Ref Des/Silkscreen Bottom")
		(1 "F.Mask" user "Board Geometry/Soldermask Top")
		(3 "B.Mask" user "Board Geometry/Soldermask Bottom")
		(17 "Dwgs.User" user "User.Drawings")
		(19 "Cmts.User" user "User.Comments")
		(21 "Eco1.User" user "User.Eco1")
		(23 "Eco2.User" user "User.Eco2")
		(25 "Edge.Cuts" user "Board Geometry/Outline")
		(27 "Margin" user)
		(31 "F.CrtYd" user "Package Geometry/Place Bound Top")
		(29 "B.CrtYd" user "Package Geometry/Place Bound Bottom")
		(35 "F.Fab" user "Ref Des/Assembly Top")
		(33 "B.Fab" user "Ref Des/Assembly Bottom")
	)
	(footprint ""
		(layer "F.Cu")
		(at 376.809 -176.18202)
		(property "Reference" "R4672"
			(at 0 0 0)
			(layer "F.SilkS")
			(hide yes)
			(effects
				(font
					(size 1.27 1.27)
				)
			)
		)
		(property "Value" ""
			(at 0 0 0)
			(layer "F.Fab")
			(effects
				(font
					(size 1.27 1.27)
				)
			)
		)
		(duplicate_pad_numbers_are_jumpers no)
		(fp_line
			(start -0.7874 -0.4064)
			(end 0.7874 -0.4064)
			(stroke
				(width 0.1524)
				(type default)
			)
			(layer "F.SilkS")
		)
		(fp_line
			(start -0.7874 0.4064)
			(end -0.7874 -0.4064)
			(stroke
				(width 0.1524)
				(type default)
			)
			(layer "F.SilkS")
		)
		(fp_line
			(start 0.7874 -0.4064)
			(end 0.7874 0.4064)
			(stroke
				(width 0.1524)
				(type default)
			)
			(layer "F.SilkS")
		)
		(fp_line
			(start 0.7874 0.4064)
			(end -0.7874 0.4064)
			(stroke
				(width 0.1524)
				(type default)
			)
			(layer "F.SilkS")
		)
		(fp_line
			(start -0.67945 -0.305054)
			(end -0.12065 -0.305054)
			(stroke
				(width 0.1)
				(type default)
			)
			(layer "F.Fab")
		)
		(fp_line
			(start -0.67945 0.3048)
			(end -0.67945 -0.305054)
			(stroke
				(width 0.1)
				(type default)
			)
			(layer "F.Fab")
		)
		(fp_line
			(start -0.12065 -0.305054)
			(end -0.12065 -0.2794)
			(stroke
				(width 0.1)
				(type default)
			)
			(layer "F.Fab")
		)
		(fp_line
			(start -0.12065 -0.2794)
			(end 0.12065 -0.2794)
			(stroke
				(width 0.1)
				(type default)
			)
			(layer "F.Fab")
		)
		(fp_line
			(start -0.12065 0.2794)
			(end -0.12065 0.3048)
			(stroke
				(width 0.1)
				(type default)
			)
			(layer "F.Fab")
		)
		(fp_line
			(start -0.12065 0.3048)
			(end -0.67945 0.3048)
			(stroke
				(width 0.1)
				(type default)
			)
			(layer "F.Fab")
		)
		(fp_line
			(start 0.120396 0.2794)
			(end -0.12065 0.2794)
			(stroke
				(width 0.1)
				(type default)
			)
			(layer "F.Fab")
		)
		(fp_line
			(start 0.120396 0.3048)
			(end 0.120396 0.2794)
			(stroke
				(width 0.1)
				(type default)
			)
			(layer "F.Fab")
		)
		(fp_line
			(start 0.12065 -0.3048)
			(end 0.67945 -0.3048)
			(stroke
				(width 0.1)
				(type default)
			)
			(layer "F.Fab")
		)
		(fp_line
			(start 0.12065 -0.2794)
			(end 0.12065 -0.3048)
			(stroke
				(width 0.1)
				(type default)
			)
			(layer "F.Fab")
		)
		(fp_line
			(start 0.67945 -0.3048)
			(end 0.67945 0.3048)
			(stroke
				(width 0.1)
				(type default)
			)
			(layer "F.Fab")
		)
		(fp_line
			(start 0.67945 0.3048)
			(end 0.120396 0.3048)
			(stroke
				(width 0.1)
				(type default)
			)
			(layer "F.Fab")
		)
		(pad "1" smd circle
			(at -0.40005 0)
			(size 0 0)
			(layers "F.Cu" "F.Mask" "F.Paste")
			(net "P3V3_AUX")
		)
		(pad "2" smd circle
			(at 0.40005 0)
			(size 0 0)
			(layers "F.Cu" "F.Mask" "F.Paste")
			(net "RST_PEX_NIC3_PERST_R_N")
		)
	)
	(footprint ""
		(layer "F.Cu")
		(at 54.856126 -32.848042 -90)
		(property "Reference" "R5878"
			(at 0 0 270)
			(layer "F.SilkS")
			(hide yes)
			(effects
				(font
					(size 1.27 1.27)
				)
			)
		)
		(property "Value" ""
			(at 0 0 270)
			(layer "F.Fab")
			(effects
				(font
					(size 1.27 1.27)
				)
			)
		)
		(duplicate_pad_numbers_are_jumpers no)
		(fp_line
			(start -0.7874 0.4064)
			(end -0.7874 -0.4064)
			(stroke
				(width 0.1524)
				(type default)
			)
			(layer "F.SilkS")
		)
		(fp_line
			(start 0.7874 0.4064)
			(end -0.7874 0.4064)
			(stroke
				(width 0.1524)
				(type default)
			)
			(layer "F.SilkS")
		)
		(fp_line
			(start -0.7874 -0.4064)
			(end 0.7874 -0.4064)
			(stroke
				(width 0.1524)
				(type default)
			)
			(layer "F.SilkS")
		)
		(fp_line
			(start 0.7874 -0.4064)
			(end 0.7874 0.4064)
			(stroke
				(width 0.1524)
				(type default)
			)
			(layer "F.SilkS")
		)
		(fp_line
			(start -0.67945 0.3048)
			(end -0.67945 -0.305054)
			(stroke
				(width 0.1)
				(type default)
			)
			(layer "F.Fab")
		)
		(fp_line
			(start -0.12065 0.3048)
			(end -0.67945 0.3048)
			(stroke
				(width 0.1)
				(type default)
			)
			(layer "F.Fab")
		)
		(fp_line
			(start 0.120396 0.3048)
			(end 0.120396 0.2794)
			(stroke
				(width 0.1)
				(type default)
			)
			(layer "F.Fab")
		)
		(fp_line
			(start 0.67945 0.3048)
			(end 0.120396 0.3048)
			(stroke
				(width 0.1)
				(type default)
			)
			(layer "F.Fab")
		)
		(fp_line
			(start -0.12065 0.2794)
			(end -0.12065 0.3048)
			(stroke
				(width 0.1)
				(type default)
			)
			(layer "F.Fab")
		)
		(fp_line
			(start 0.120396 0.2794)
			(end -0.12065 0.2794)
			(stroke
				(width 0.1)
				(type default)
			)
			(layer "F.Fab")
		)
		(fp_line
			(start -0.12065 -0.2794)
			(end 0.12065 -0.2794)
			(stroke
				(width 0.1)
				(type default)
			)
			(layer "F.Fab")
		)
		(fp_line
			(start 0.12065 -0.2794)
			(end 0.12065 -0.3048)
			(stroke
				(width 0.1)
				(type default)
			)
			(layer "F.Fab")
		)
		(fp_line
			(start 0.12065 -0.3048)
			(end 0.67945 -0.3048)
			(stroke
				(width 0.1)
				(type default)
			)
			(layer "F.Fab")
		)
		(fp_line
			(start 0.67945 -0.3048)
			(end 0.67945 0.3048)
			(stroke
				(width 0.1)
				(type default)
			)
			(layer "F.Fab")
		)
		(fp_line
			(start -0.67945 -0.305054)
			(end -0.12065 -0.305054)
			(stroke
				(width 0.1)
				(type default)
			)
			(layer "F.Fab")
		)
		(fp_line
			(start -0.12065 -0.305054)
			(end -0.12065 -0.2794)
			(stroke
				(width 0.1)
				(type default)
			)
			(layer "F.Fab")
		)
		(pad "1" smd circle
			(at -0.40005 0 270)
			(size 0 0)
			(layers "F.Cu" "F.Mask" "F.Paste")
			(net "SSD2_AUX_P3V3_EN_R")
		)
		(pad "2" smd circle
			(at 0.40005 0 270)
			(size 0 0)
			(layers "F.Cu" "F.Mask" "F.Paste")
			(net "P3V3_SSD2_CO_EN")
		)
	)
	(footprint ""
		(layer "F.Cu")
		(at 386.90804 -160.380934)
		(property "Reference" "R329"
			(at 0 0 0)
			(layer "F.SilkS")
			(hide yes)
			(effects
				(font
					(size 1.27 1.27)
				)
			)
		)
		(property "Value" ""
			(at 0 0 0)
			(layer "F.Fab")
			(effects
				(font
					(size 1.27 1.27)
				)
			)
		)
		(duplicate_pad_numbers_are_jumpers no)
		(fp_line
			(start -0.7874 -0.4064)
			(end 0.7874 -0.4064)
			(stroke
				(width 0.1524)
				(type default)
			)
			(layer "F.SilkS")
		)
		(fp_line
			(start -0.7874 0.4064)
			(end -0.7874 -0.4064)
			(stroke
				(width 0.1524)
				(type default)
			)
			(layer "F.SilkS")
		)
		(fp_line
			(start 0.7874 -0.4064)
			(end 0.7874 0.4064)
			(stroke
				(width 0.1524)
				(type default)
			)
			(layer "F.SilkS")
		)
		(fp_line
			(start 0.7874 0.4064)
			(end -0.7874 0.4064)
			(stroke
				(width 0.1524)
				(type default)
			)
			(layer "F.SilkS")
		)
		(fp_line
			(start -0.67945 -0.305054)
			(end -0.12065 -0.305054)
			(stroke
				(width 0.1)
				(type default)
			)
			(layer "F.Fab")
		)
		(fp_line
			(start -0.67945 0.3048)
			(end -0.67945 -0.305054)
			(stroke
				(width 0.1)
				(type default)
			)
			(layer "F.Fab")
		)
		(fp_line
			(start -0.12065 -0.305054)
			(end -0.12065 -0.2794)
			(stroke
				(width 0.1)
				(type default)
			)
			(layer "F.Fab")
		)
		(fp_line
			(start -0.12065 -0.2794)
			(end 0.12065 -0.2794)
			(stroke
				(width 0.1)
				(type default)
			)
			(layer "F.Fab")
		)
		(fp_line
			(start -0.12065 0.2794)
			(end -0.12065 0.3048)
			(stroke
				(width 0.1)
				(type default)
			)
			(layer "F.Fab")
		)
		(fp_line
			(start -0.12065 0.3048)
			(end -0.67945 0.3048)
			(stroke
				(width 0.1)
				(type default)
			)
			(layer "F.Fab")
		)
		(fp_line
			(start 0.120396 0.2794)
			(end -0.12065 0.2794)
			(stroke
				(width 0.1)
				(type default)
			)
			(layer "F.Fab")
		)
		(fp_line
			(start 0.120396 0.3048)
			(end 0.120396 0.2794)
			(stroke
				(width 0.1)
				(type default)
			)
			(layer "F.Fab")
		)
		(fp_line
			(start 0.12065 -0.3048)
			(end 0.67945 -0.3048)
			(stroke
				(width 0.1)
				(type default)
			)
			(layer "F.Fab")
		)
		(fp_line
			(start 0.12065 -0.2794)
			(end 0.12065 -0.3048)
			(stroke
				(width 0.1)
				(type default)
			)
			(layer "F.Fab")
		)
		(fp_line
			(start 0.67945 -0.3048)
			(end 0.67945 0.3048)
			(stroke
				(width 0.1)
				(type default)
			)
			(layer "F.Fab")
		)
		(fp_line
			(start 0.67945 0.3048)
			(end 0.120396 0.3048)
			(stroke
				(width 0.1)
				(type default)
			)
			(layer "F.Fab")
		)
		(pad "1" smd circle
			(at -0.40005 0)
			(size 0 0)
			(layers "F.Cu" "F.Mask" "F.Paste")
			(net "NIC6_MAIN_PWR_EN")
		)
		(pad "2" smd circle
			(at 0.40005 0)
			(size 0 0)
			(layers "F.Cu" "F.Mask" "F.Paste")
			(net "GND")
		)
	)
	(footprint ""
		(layer "F.Cu")
		(at 214.757 -207.264)
		(property "Reference" "U119"
			(at -4.578604 2.039112 0)
			(unlocked yes)
			(layer "F.SilkS")
			(effects
				(font
					(size 0.7874 0.5842)
					(thickness 0.1524)
				)
				(justify left)
			)
		)
		(property "Value" ""
			(at 0 0 0)
			(layer "F.Fab")
			(effects
				(font
					(size 1.27 1.27)
				)
			)
		)
		(duplicate_pad_numbers_are_jumpers no)
		(fp_line
			(start -1.3208 -1.525016)
			(end -0.508 -1.525016)
			(stroke
				(width 0.1524)
				(type default)
			)
			(layer "F.SilkS")
		)
		(fp_line
			(start -1.3208 1.525016)
			(end -1.3208 -1.525016)
			(stroke
				(width 0.1524)
				(type default)
			)
			(layer "F.SilkS")
		)
		(fp_line
			(start -0.508 -1.525016)
			(end 0 -0.999998)
			(stroke
				(width 0.1524)
				(type default)
			)
			(layer "F.SilkS")
		)
		(fp_line
			(start 0 -0.999998)
			(end 0.508 -1.525016)
			(stroke
				(width 0.1524)
				(type default)
			)
			(layer "F.SilkS")
		)
		(fp_line
			(start 0.508 -1.525016)
			(end 1.3208 -1.525016)
			(stroke
				(width 0.1524)
				(type default)
			)
			(layer "F.SilkS")
		)
		(fp_line
			(start 1.3208 -1.525016)
			(end 1.3208 1.525016)
			(stroke
				(width 0.1524)
				(type default)
			)
			(layer "F.SilkS")
		)
		(fp_line
			(start 1.3208 1.525016)
			(end -1.3208 1.525016)
			(stroke
				(width 0.1524)
				(type default)
			)
			(layer "F.SilkS")
		)
		(fp_poly
			(pts
				(xy -2.86512 -1.320038) (xy -3.673348 -1.589532) (xy -3.13436 -2.128266)
			)
			(stroke
				(width 0)
				(type default)
			)
			(fill yes)
			(layer "F.SilkS")
		)
		(fp_line
			(start -3.037078 -1.20777)
			(end -1.524 -1.20777)
			(stroke
				(width 0.1)
				(type default)
			)
			(layer "F.Fab")
		)
		(fp_line
			(start -3.037078 1.203706)
			(end -3.037078 -1.20777)
			(stroke
				(width 0.1)
				(type default)
			)
			(layer "F.Fab")
		)
		(fp_line
			(start -1.5494 1.203706)
			(end -3.037078 1.203706)
			(stroke
				(width 0.1)
				(type default)
			)
			(layer "F.Fab")
		)
		(fp_line
			(start -1.5494 1.5494)
			(end -1.5494 1.203706)
			(stroke
				(width 0.1)
				(type default)
			)
			(layer "F.Fab")
		)
		(fp_line
			(start -1.524 -1.524)
			(end 1.524 -1.524)
			(stroke
				(width 0.1)
				(type default)
			)
			(layer "F.Fab")
		)
		(fp_line
			(start -1.524 -1.20777)
			(end -1.524 -1.524)
			(stroke
				(width 0.1)
				(type default)
			)
			(layer "F.Fab")
		)
		(fp_line
			(start 1.524 -1.524)
			(end 1.524 -1.20777)
			(stroke
				(width 0.1)
				(type default)
			)
			(layer "F.Fab")
		)
		(fp_line
			(start 1.524 -1.20777)
			(end 3.0353 -1.20777)
			(stroke
				(width 0.1)
				(type default)
			)
			(layer "F.Fab")
		)
		(fp_line
			(start 1.524 1.208786)
			(end 1.524 1.5494)
			(stroke
				(width 0.1)
				(type default)
			)
			(layer "F.Fab")
		)
		(fp_line
			(start 1.524 1.5494)
			(end -1.5494 1.5494)
			(stroke
				(width 0.1)
				(type default)
			)
			(layer "F.Fab")
		)
		(fp_line
			(start 3.0353 -1.20777)
			(end 3.0353 1.208786)
			(stroke
				(width 0.1)
				(type default)
			)
			(layer "F.Fab")
		)
		(fp_line
			(start 3.0353 1.208786)
			(end 1.524 1.208786)
			(stroke
				(width 0.1)
				(type default)
			)
			(layer "F.Fab")
		)
		(fp_poly
			(pts
				(xy -3.175 -1.016) (xy -3.937 -0.635) (xy -3.937 -1.397)
			)
			(stroke
				(width 0)
				(type default)
			)
			(fill yes)
			(layer "F.Fab")
		)
		(pad "1" smd rect
			(at -2.234946 -0.975106 270)
			(size 0.3556 1.4986)
			(layers "F.Cu" "F.Mask" "F.Paste")
			(net "P1V2_AUX")
		)
		(pad "2" smd rect
			(at -2.234946 -0.32512 270)
			(size 0.3556 1.4986)
			(layers "F.Cu" "F.Mask" "F.Paste")
			(net "SMB_NIC4_R_SDA")
		)
		(pad "3" smd rect
			(at -2.234946 0.32512 270)
			(size 0.3556 1.4986)
			(layers "F.Cu" "F.Mask" "F.Paste")
			(net "SMB_NIC4_R_SCL")
		)
		(pad "4" smd rect
			(at -2.234946 0.975106 270)
			(size 0.3556 1.4986)
			(layers "F.Cu" "F.Mask" "F.Paste")
			(net "GND")
		)
		(pad "5" smd rect
			(at 2.234946 0.975106 270)
			(size 0.3556 1.4986)
			(layers "F.Cu" "F.Mask" "F.Paste")
			(net "SMB_NIC4_LS_EN")
		)
		(pad "6" smd rect
			(at 2.234946 0.32512 270)
			(size 0.3556 1.4986)
			(layers "F.Cu" "F.Mask" "F.Paste")
			(net "SMB_NIC4_LS_R_SCL")
		)
		(pad "7" smd rect
			(at 2.234946 -0.32512 270)
			(size 0.3556 1.4986)
			(layers "F.Cu" "F.Mask" "F.Paste")
			(net "SMB_NIC4_LS_R_SDA")
		)
		(pad "8" smd rect
			(at 2.234946 -0.975106 270)
			(size 0.3556 1.4986)
			(layers "F.Cu" "F.Mask" "F.Paste")
			(net "P3V3_NIC4")
		)
	)
	(footprint ""
		(layer "F.Cu")
		(at 355.854 -234.061 -90)
		(property "Reference" "R3593"
			(at 0 0 270)
			(layer "F.SilkS")
			(hide yes)
			(effects
				(font
					(size 1.27 1.27)
				)
			)
		)
		(property "Value" ""
			(at 0 0 270)
			(layer "F.Fab")
			(effects
				(font
					(size 1.27 1.27)
				)
			)
		)
		(duplicate_pad_numbers_are_jumpers no)
		(fp_line
			(start -0.7874 0.4064)
			(end -0.7874 -0.4064)
			(stroke
				(width 0.1524)
				(type default)
			)
			(layer "F.SilkS")
		)
		(fp_line
			(start 0.7874 0.4064)
			(end -0.7874 0.4064)
			(stroke
				(width 0.1524)
				(type default)
			)
			(layer "F.SilkS")
		)
		(fp_line
			(start -0.7874 -0.4064)
			(end 0.7874 -0.4064)
			(stroke
				(width 0.1524)
				(type default)
			)
			(layer "F.SilkS")
		)
		(fp_line
			(start 0.7874 -0.4064)
			(end 0.7874 0.4064)
			(stroke
				(width 0.1524)
				(type default)
			)
			(layer "F.SilkS")
		)
		(fp_line
			(start -0.67945 0.3048)
			(end -0.67945 -0.305054)
			(stroke
				(width 0.1)
				(type default)
			)
			(layer "F.Fab")
		)
		(fp_line
			(start -0.12065 0.3048)
			(end -0.67945 0.3048)
			(stroke
				(width 0.1)
				(type default)
			)
			(layer "F.Fab")
		)
		(fp_line
			(start 0.120396 0.3048)
			(end 0.120396 0.2794)
			(stroke
				(width 0.1)
				(type default)
			)
			(layer "F.Fab")
		)
		(fp_line
			(start 0.67945 0.3048)
			(end 0.120396 0.3048)
			(stroke
				(width 0.1)
				(type default)
			)
			(layer "F.Fab")
		)
		(fp_line
			(start -0.12065 0.2794)
			(end -0.12065 0.3048)
			(stroke
				(width 0.1)
				(type default)
			)
			(layer "F.Fab")
		)
		(fp_line
			(start 0.120396 0.2794)
			(end -0.12065 0.2794)
			(stroke
				(width 0.1)
				(type default)
			)
			(layer "F.Fab")
		)
		(fp_line
			(start -0.12065 -0.2794)
			(end 0.12065 -0.2794)
			(stroke
				(width 0.1)
				(type default)
			)
			(layer "F.Fab")
		)
		(fp_line
			(start 0.12065 -0.2794)
			(end 0.12065 -0.3048)
			(stroke
				(width 0.1)
				(type default)
			)
			(layer "F.Fab")
		)
		(fp_line
			(start 0.12065 -0.3048)
			(end 0.67945 -0.3048)
			(stroke
				(width 0.1)
				(type default)
			)
			(layer "F.Fab")
		)
		(fp_line
			(start 0.67945 -0.3048)
			(end 0.67945 0.3048)
			(stroke
				(width 0.1)
				(type default)
			)
			(layer "F.Fab")
		)
		(fp_line
			(start -0.67945 -0.305054)
			(end -0.12065 -0.305054)
			(stroke
				(width 0.1)
				(type default)
			)
			(layer "F.Fab")
		)
		(fp_line
			(start -0.12065 -0.305054)
			(end -0.12065 -0.2794)
			(stroke
				(width 0.1)
				(type default)
			)
			(layer "F.Fab")
		)
		(pad "1" smd circle
			(at -0.40005 0 270)
			(size 0 0)
			(layers "F.Cu" "F.Mask" "F.Paste")
			(net "SSD7_PWRDIS_R")
		)
		(pad "2" smd circle
			(at 0.40005 0 270)
			(size 0 0)
			(layers "F.Cu" "F.Mask" "F.Paste")
			(net "SSD7_PWRDIS")
		)
	)
)
